# SCM (Grand Teton) — schematic netlist excerpt (pin names and nets, part order shuffled) for the footprints in the layout excerpt that follows; sources: Cadence DE-HDL packaged netlist, KiCad conversion of 12092022_DA0F0TMDCD0_F0T_Management_Board_D_brd_V3_OCP.brd

R795  Q_RES  1K 1% CHIP  pkg 0402LF  page 15 : A = P1V2_AUX ; B = P1V2_SENSOR
R669  Q_RES  0 5% CHIP  pkg 0402LF  page 47 : A = LED_POSTCODE_7 ; B = LED_POSTCODE_7_R1

(kicad_pcb
	(version 20260206)
	(generator "pcbnew")
	(generator_version "10.0")
	(general
		(thickness 1.6)
		(legacy_teardrops no)
	)
	(paper "A4")
	(title_block
		(title "12092022_DA0F0TMDCD0_F0T_Management_Board_D_brd_V3_OCP.brd")
		(comment 1 "Grand Teton / footprints 1279-1280 of 1440")
	)
	(layers
		(0 "F.Cu" signal "TOP")
		(4 "In1.Cu" signal "GND")
		(6 "In2.Cu" signal "IN1")
		(8 "In3.Cu" signal "GND1")
		(10 "In4.Cu" signal "IN2")
		(12 "In5.Cu" signal "VCC")
		(14 "In6.Cu" signal "VCC1")
		(16 "In7.Cu" signal "IN3")
		(18 "In8.Cu" signal "GND2")
		(20 "In9.Cu" signal "IN4")
		(22 "In10.Cu" signal "GND3")
		(2 "B.Cu" signal "BOTTOM")
		(9 "F.Adhes" user "F.Adhesive")
		(11 "B.Adhes" user "B.Adhesive")
		(13 "F.Paste" user "Package Geometry/Pastemask Top")
		(15 "B.Paste" user "Package Geometry/Pastemask Bottom")
		(5 "F.SilkS" user "Ref Des/Silkscreen Top")
		(7 "B.SilkS" user "Ref Des/Silkscreen Bottom")
		(1 "F.Mask" user "Board Geometry/Soldermask Top")
		(3 "B.Mask" user "Board Geometry/Soldermask Bottom")
		(17 "Dwgs.User" user "User.Drawings")
		(19 "Cmts.User" user "User.Comments")
		(21 "Eco1.User" user "User.Eco1")
		(23 "Eco2.User" user "User.Eco2")
		(25 "Edge.Cuts" user "Board Geometry/Outline")
		(27 "Margin" user)
		(31 "F.CrtYd" user "Package Geometry/Place Bound Top")
		(29 "B.CrtYd" user "Package Geometry/Place Bound Bottom")
		(35 "F.Fab" user "Ref Des/Assembly Top")
		(33 "B.Fab" user "Ref Des/Assembly Bottom")
	)
	(footprint ""
		(layer "B.Cu")
		(at 55.14848 -74.242676 -90)
		(property "Reference" "R795"
			(at 0 0 90)
			(layer "B.SilkS")
			(hide yes)
			(effects
				(font
					(size 1.27 1.27)
				)
				(justify mirror)
			)
		)
		(property "Value" ""
			(at 0 0 90)
			(layer "B.Fab")
			(effects
				(font
					(size 1.27 1.27)
				)
				(justify mirror)
			)
		)
		(duplicate_pad_numbers_are_jumpers no)
		(fp_line
			(start -0.7874 0.4064)
			(end 0.7874 0.4064)
			(stroke
				(width 0.1524)
				(type default)
			)
			(layer "B.SilkS")
		)
		(fp_line
			(start 0.7874 0.4064)
			(end 0.7874 -0.4064)
			(stroke
				(width 0.1524)
				(type default)
			)
			(layer "B.SilkS")
		)
		(fp_line
			(start -0.7874 -0.4064)
			(end -0.7874 0.4064)
			(stroke
				(width 0.1524)
				(type default)
			)
			(layer "B.SilkS")
		)
		(fp_line
			(start 0.7874 -0.4064)
			(end -0.7874 -0.4064)
			(stroke
				(width 0.1524)
				(type default)
			)
			(layer "B.SilkS")
		)
		(fp_line
			(start -0.67945 0.3048)
			(end -0.120396 0.3048)
			(stroke
				(width 0.1)
				(type default)
			)
			(layer "B.Fab")
		)
		(fp_line
			(start -0.120396 0.3048)
			(end -0.120396 0.2794)
			(stroke
				(width 0.1)
				(type default)
			)
			(layer "B.Fab")
		)
		(fp_line
			(start 0.12065 0.3048)
			(end 0.67945 0.3048)
			(stroke
				(width 0.1)
				(type default)
			)
			(layer "B.Fab")
		)
		(fp_line
			(start 0.67945 0.3048)
			(end 0.67945 -0.305054)
			(stroke
				(width 0.1)
				(type default)
			)
			(layer "B.Fab")
		)
		(fp_line
			(start -0.120396 0.2794)
			(end 0.12065 0.2794)
			(stroke
				(width 0.1)
				(type default)
			)
			(layer "B.Fab")
		)
		(fp_line
			(start 0.12065 0.2794)
			(end 0.12065 0.3048)
			(stroke
				(width 0.1)
				(type default)
			)
			(layer "B.Fab")
		)
		(fp_line
			(start -0.12065 -0.2794)
			(end -0.12065 -0.3048)
			(stroke
				(width 0.1)
				(type default)
			)
			(layer "B.Fab")
		)
		(fp_line
			(start 0.12065 -0.2794)
			(end -0.12065 -0.2794)
			(stroke
				(width 0.1)
				(type default)
			)
			(layer "B.Fab")
		)
		(fp_line
			(start -0.67945 -0.3048)
			(end -0.67945 0.3048)
			(stroke
				(width 0.1)
				(type default)
			)
			(layer "B.Fab")
		)
		(fp_line
			(start -0.12065 -0.3048)
			(end -0.67945 -0.3048)
			(stroke
				(width 0.1)
				(type default)
			)
			(layer "B.Fab")
		)
		(fp_line
			(start 0.12065 -0.305054)
			(end 0.12065 -0.2794)
			(stroke
				(width 0.1)
				(type default)
			)
			(layer "B.Fab")
		)
		(fp_line
			(start 0.67945 -0.305054)
			(end 0.12065 -0.305054)
			(stroke
				(width 0.1)
				(type default)
			)
			(layer "B.Fab")
		)
		(pad "1" smd circle
			(at 0.40005 0 90)
			(size 0 0)
			(layers "B.Cu" "B.Mask" "B.Paste")
			(net "P1V2_AUX")
		)
		(pad "2" smd circle
			(at -0.40005 0 90)
			(size 0 0)
			(layers "B.Cu" "B.Mask" "B.Paste")
			(net "P1V2_SENSOR")
		)
	)
	(footprint ""
		(layer "B.Cu")
		(at 74.803 -32.131 180)
		(property "Reference" "R669"
			(at 0 0 0)
			(layer "B.SilkS")
			(hide yes)
			(effects
				(font
					(size 1.27 1.27)
				)
				(justify mirror)
			)
		)
		(property "Value" ""
			(at 0 0 0)
			(layer "B.Fab")
			(effects
				(font
					(size 1.27 1.27)
				)
				(justify mirror)
			)
		)
		(duplicate_pad_numbers_are_jumpers no)
		(fp_line
			(start 0.7874 0.4064)
			(end 0.7874 -0.4064)
			(stroke
				(width 0.1524)
				(type default)
			)
			(layer "B.SilkS")
		)
		(fp_line
			(start 0.7874 -0.4064)
			(end -0.7874 -0.4064)
			(stroke
				(width 0.1524)
				(type default)
			)
			(layer "B.SilkS")
		)
		(fp_line
			(start -0.7874 0.4064)
			(end 0.7874 0.4064)
			(stroke
				(width 0.1524)
				(type default)
			)
			(layer "B.SilkS")
		)
		(fp_line
			(start -0.7874 -0.4064)
			(end -0.7874 0.4064)
			(stroke
				(width 0.1524)
				(type default)
			)
			(layer "B.SilkS")
		)
		(fp_line
			(start 0.67945 0.3048)
			(end 0.67945 -0.305054)
			(stroke
				(width 0.1)
				(type default)
			)
			(layer "B.Fab")
		)
		(fp_line
			(start 0.67945 -0.305054)
			(end 0.12065 -0.305054)
			(stroke
				(width 0.1)
				(type default)
			)
			(layer "B.Fab")
		)
		(fp_line
			(start 0.12065 0.3048)
			(end 0.67945 0.3048)
			(stroke
				(width 0.1)
				(type default)
			)
			(layer "B.Fab")
		)
		(fp_line
			(start 0.12065 0.2794)
			(end 0.12065 0.3048)
			(stroke
				(width 0.1)
				(type default)
			)
			(layer "B.Fab")
		)
		(fp_line
			(start 0.12065 -0.2794)
			(end -0.12065 -0.2794)
			(stroke
				(width 0.1)
				(type default)
			)
			(layer "B.Fab")
		)
		(fp_line
			(start 0.12065 -0.305054)
			(end 0.12065 -0.2794)
			(stroke
				(width 0.1)
				(type default)
			)
			(layer "B.Fab")
		)
		(fp_line
			(start -0.120396 0.3048)
			(end -0.120396 0.2794)
			(stroke
				(width 0.1)
				(type default)
			)
			(layer "B.Fab")
		)
		(fp_line
			(start -0.120396 0.2794)
			(end 0.12065 0.2794)
			(stroke
				(width 0.1)
				(type default)
			)
			(layer "B.Fab")
		)
		(fp_line
			(start -0.12065 -0.2794)
			(end -0.12065 -0.3048)
			(stroke
				(width 0.1)
				(type default)
			)
			(layer "B.Fab")
		)
		(fp_line
			(start -0.12065 -0.3048)
			(end -0.67945 -0.3048)
			(stroke
				(width 0.1)
				(type default)
			)
			(layer "B.Fab")
		)
		(fp_line
			(start -0.67945 0.3048)
			(end -0.120396 0.3048)
			(stroke
				(width 0.1)
				(type default)
			)
			(layer "B.Fab")
		)
		(fp_line
			(start -0.67945 -0.3048)
			(end -0.67945 0.3048)
			(stroke
				(width 0.1)
				(type default)
			)
			(layer "B.Fab")
		)
		(pad "1" smd circle
			(at 0.40005 0)
			(size 0 0)
			(layers "B.Cu" "B.Mask" "B.Paste")
			(net "LED_POSTCODE_7")
		)
		(pad "2" smd circle
			(at -0.40005 0)
			(size 0 0)
			(layers "B.Cu" "B.Mask" "B.Paste")
			(net "LED_POSTCODE_7_R1")
		)
	)
)
